(kicad_pcb
	(version 20260206)
	(generator "pcbnew")
	(generator_version "10.0")
	(general
		(thickness 1.21888)
		(legacy_teardrops no)
	)
	(paper "A4")
	(title_block
		(title "timecard-proto-v0 — Timingcard_PCB.PcbDoc")
		(comment 1 "Time Appliance Project (Time Card) / footprints 15-26 of 167")
	)
	(layers
		(0 "F.Cu" signal "TOP")
		(4 "In1.Cu" signal "SGND")
		(6 "In2.Cu" signal "IN1")
		(8 "In3.Cu" signal "IN2")
		(10 "In4.Cu" signal "SGND1")
		(2 "B.Cu" signal "BOTTOM")
		(9 "F.Adhes" user "F.Adhesive")
		(11 "B.Adhes" user "B.Adhesive")
		(13 "F.Paste" user "Top Paste")
		(15 "B.Paste" user "Bottom Paste")
		(5 "F.SilkS" user "Top Overlay")
		(7 "B.SilkS" user "Bottom Overlay")
		(1 "F.Mask" user "Top Solder")
		(3 "B.Mask" user "Bottom Solder")
		(17 "Dwgs.User" user "User.Drawings")
		(19 "Cmts.User" user "User.Comments")
		(21 "Eco1.User" user "User.Eco1")
		(23 "Eco2.User" user "User.Eco2")
		(25 "Edge.Cuts" user)
		(27 "Margin" user)
		(31 "F.CrtYd" user "Top Courtyard")
		(29 "B.CrtYd" user "Bottom Courtyard")
		(35 "F.Fab" user "Top Component Center")
		(33 "B.Fab" user "Bottom Component Center")
	)
	(footprint "Capacitors:CAPC2012X14N"
		(layer "F.Cu")
		(at 162.751595 63.9046 -90)
		(property "Reference" "C54"
			(at -2.926 -1.830345 90)
			(unlocked yes)
			(layer "F.SilkS")
			(effects
				(font
					(size 0.762 0.762)
					(thickness 0.2286)
				)
				(justify left bottom)
			)
		)
		(property "Value" "CAP_0805_1UF_25V"
			(at 3.52679 1.5875 0)
			(unlocked yes)
			(layer "F.SilkS")
			(hide yes)
			(effects
				(font
					(size 1.524 1.524)
					(thickness 0.254)
				)
				(justify left bottom)
			)
		)
		(sheetname "UART")
		(sheetfile "UART.kicad_sch")
		(duplicate_pad_numbers_are_jumpers no)
		(fp_line
			(start 0.762 0.9652)
			(end -0.762 0.9652)
			(stroke
				(width 0.1524)
				(type solid)
			)
			(layer "F.SilkS")
		)
		(fp_line
			(start 0.762 -0.9652)
			(end -0.762 -0.9652)
			(stroke
				(width 0.1524)
				(type solid)
			)
			(layer "F.SilkS")
		)
		(pad "1" smd rect
			(at -0.9 0)
			(size 1.45 1.15)
			(layers "F.Cu" "F.Mask" "F.Paste")
			(net "GND")
		)
		(pad "2" smd rect
			(at 0.9 0)
			(size 1.45 1.15)
			(layers "F.Cu" "F.Mask" "F.Paste")
			(net "NetC54_2")
		)
	)
	(footprint "Modules:RCB-F9T"
		(locked yes)
		(layer "F.Cu")
		(at 126.126095 91.5736 90)
		(property "Reference" "U9"
			(at 25.162655 -6.9605 0)
			(unlocked yes)
			(layer "F.SilkS")
			(effects
				(font
					(size 0.762 0.762)
					(thickness 0.2286)
				)
				(justify left bottom)
			)
		)
		(property "Value" "RCB-F9T"
			(at 6.55051 -25.6882 0)
			(unlocked yes)
			(layer "F.SilkS")
			(hide yes)
			(effects
				(font
					(size 1.524 1.524)
					(thickness 0.254)
				)
				(justify left bottom)
			)
		)
		(sheetname "GPS_IMU_SENSORS")
		(sheetfile "GPS_IMU_SENSORS.kicad_sch")
		(duplicate_pad_numbers_are_jumpers no)
		(fp_line
			(start 31.75 -67.18)
			(end 31.75 0)
			(stroke
				(width 0.254)
				(type solid)
			)
			(layer "F.SilkS")
		)
		(fp_line
			(start 0 -67.18)
			(end 31.75 -67.18)
			(stroke
				(width 0.254)
				(type solid)
			)
			(layer "F.SilkS")
		)
		(fp_line
			(start 0 -67.18)
			(end 0 0)
			(stroke
				(width 0.254)
				(type solid)
			)
			(layer "F.SilkS")
		)
		(fp_line
			(start 0 0)
			(end 31.75 0)
			(stroke
				(width 0.254)
				(type solid)
			)
			(layer "F.SilkS")
		)
		(fp_circle
			(center 28.875 -63.84)
			(end 30.425 -63.84)
			(stroke
				(width 0.254)
				(type solid)
			)
			(fill no)
			(layer "F.SilkS")
		)
		(fp_circle
			(center 2.875 -63.84)
			(end 4.425 -63.84)
			(stroke
				(width 0.254)
				(type solid)
			)
			(fill no)
			(layer "F.SilkS")
		)
		(fp_circle
			(center 28.875 -3.34)
			(end 30.425 -3.34)
			(stroke
				(width 0.254)
				(type solid)
			)
			(fill no)
			(layer "F.SilkS")
		)
		(fp_circle
			(center 2.875 -3.34)
			(end 4.425 -3.34)
			(stroke
				(width 0.254)
				(type solid)
			)
			(fill no)
			(layer "F.SilkS")
		)
		(pad "0" thru_hole circle
			(at 18.47 -6.11 90)
			(size 0 0)
			(drill 0.76)
			(layers "*.Cu" "*.Mask")
			(remove_unused_layers no)
			(thermal_bridge_angle 90)
		)
		(pad "0" thru_hole circle
			(at 22.47 -6.11 90)
			(size 0 0)
			(drill 0.76)
			(layers "*.Cu" "*.Mask")
			(remove_unused_layers no)
			(thermal_bridge_angle 90)
		)
		(pad "1" smd rect
			(at 23.47 -3.8875 90)
			(size 1.12 2.105)
			(layers "F.Cu" "F.Mask" "F.Paste")
			(net "+5.0V")
		)
		(pad "2" smd rect
			(at 23.47 -8.3325 90)
			(size 1.12 2.105)
			(layers "F.Cu" "F.Mask" "F.Paste")
			(net "+3.3V")
		)
		(pad "3" smd rect
			(at 21.47 -3.8875 90)
			(size 1.12 2.105)
			(layers "F.Cu" "F.Mask" "F.Paste")
			(net "GPS1_TX")
		)
		(pad "4" smd rect
			(at 21.47 -8.3325 90)
			(size 1.12 2.105)
			(layers "F.Cu" "F.Mask" "F.Paste")
			(net "GPS1_RST")
		)
		(pad "5" smd rect
			(at 19.47 -3.8875 90)
			(size 1.12 2.105)
			(layers "F.Cu" "F.Mask" "F.Paste")
			(net "GPS1_RX")
		)
		(pad "6" smd rect
			(at 19.47 -8.3325 90)
			(size 1.12 2.105)
			(layers "F.Cu" "F.Mask" "F.Paste")
			(net "GPS1_TP1")
		)
		(pad "7" smd rect
			(at 17.47 -3.8875 90)
			(size 1.12 2.105)
			(layers "F.Cu" "F.Mask" "F.Paste")
			(net "GPS1_TP2")
		)
		(pad "8" smd rect
			(at 17.47 -8.3325 90)
			(size 1.12 2.105)
			(layers "F.Cu" "F.Mask" "F.Paste")
			(net "GND")
		)
	)
	(footprint "Passives:FUSM1608X60N"
		(layer "F.Cu")
		(at 212.484795 70.2546 180)
		(property "Reference" "F1"
			(at 0.7962 0.882655 0)
			(unlocked yes)
			(layer "F.SilkS")
			(effects
				(font
					(size 0.762 0.762)
					(thickness 0.2286)
				)
				(justify left bottom)
			)
		)
		(property "Value" "FUSE_0603_2.00A"
			(at 2.8829 -4.39039 0)
			(unlocked yes)
			(layer "F.SilkS")
			(hide yes)
			(effects
				(font
					(size 1.524 1.524)
					(thickness 0.254)
				)
				(justify left bottom)
			)
		)
		(sheetname "POWER")
		(sheetfile "POWER.kicad_sch")
		(duplicate_pad_numbers_are_jumpers no)
		(fp_line
			(start 0 -0.5)
			(end 0 0.5)
			(stroke
				(width 0.1524)
				(type solid)
			)
			(layer "F.SilkS")
		)
		(pad "1" smd rect
			(at -0.69 0 270)
			(size 1 0.72)
			(layers "F.Cu" "F.Mask" "F.Paste")
			(net "NetD2_1")
		)
		(pad "2" smd rect
			(at 0.69 0 270)
			(size 1 0.72)
			(layers "F.Cu" "F.Mask" "F.Paste")
			(net "+12V")
		)
	)
	(footprint "Vault:CAPC1608X87X45ML20T05"
		(layer "F.Cu")
		(at 171.641595 82.8276 -90)
		(property "Reference" "C83"
			(at -2.649 -1.565345 90)
			(unlocked yes)
			(layer "F.SilkS")
			(effects
				(font
					(size 0.762 0.762)
					(thickness 0.2286)
				)
				(justify left bottom)
			)
		)
		(property "Value" "0.1uF"
			(at 3.47599 0.2921 0)
			(unlocked yes)
			(layer "F.SilkS")
			(hide yes)
			(effects
				(font
					(size 1.524 1.524)
					(thickness 0.254)
				)
				(justify left bottom)
			)
		)
		(sheetname "MAC")
		(sheetfile "MAC.kicad_sch")
		(duplicate_pad_numbers_are_jumpers no)
		(pad "1" smd rect
			(at -0.7 0)
			(size 1.1 1.05)
			(layers "F.Cu" "F.Mask" "F.Paste")
			(net "GND")
		)
		(pad "2" smd rect
			(at 0.7 0)
			(size 1.1 1.05)
			(layers "F.Cu" "F.Mask" "F.Paste")
			(net "+3.3V_CLEAN")
		)
	)
	(footprint "Connectors:CUI_PJ-002A"
		(layer "F.Cu")
		(at 213.932595 63.5546 90)
		(property "Reference" "J1"
			(at 8.510345 5.38505 0)
			(unlocked yes)
			(layer "F.SilkS")
			(effects
				(font
					(size 0.762 0.762)
					(thickness 0.2286)
				)
				(justify left bottom)
			)
		)
		(property "Value" "PJ-002A"
			(at -4.87299 -6.1849 0)
			(unlocked yes)
			(layer "F.SilkS")
			(hide yes)
			(effects
				(font
					(size 1.524 1.524)
					(thickness 0.254)
				)
				(justify left bottom)
			)
		)
		(sheetname "POWER")
		(sheetfile "POWER.kicad_sch")
		(duplicate_pad_numbers_are_jumpers no)
		(fp_line
			(start 9.8 -5.334)
			(end 9.8 4.826)
			(stroke
				(width 0.2032)
				(type solid)
			)
			(layer "F.SilkS")
		)
		(fp_line
			(start 5.55 -5.334)
			(end 9.8 -5.334)
			(stroke
				(width 0.2032)
				(type solid)
			)
			(layer "F.SilkS")
		)
		(fp_line
			(start -0.7 -5.334)
			(end 0.45 -5.334)
			(stroke
				(width 0.2032)
				(type solid)
			)
			(layer "F.SilkS")
		)
		(fp_line
			(start -0.7 -5.334)
			(end -0.7 -2.55)
			(stroke
				(width 0.2032)
				(type solid)
			)
			(layer "F.SilkS")
		)
		(fp_line
			(start -0.7 2.65)
			(end -0.7 4.826)
			(stroke
				(width 0.2032)
				(type solid)
			)
			(layer "F.SilkS")
		)
		(fp_line
			(start -0.7 4.826)
			(end 9.8 4.826)
			(stroke
				(width 0.2032)
				(type solid)
			)
			(layer "F.SilkS")
		)
		(fp_circle
			(center -2 0)
			(end -1.8 0)
			(stroke
				(width 0.4)
				(type solid)
			)
			(fill no)
			(layer "F.SilkS")
		)
		(pad "1" thru_hole oval
			(at 0 0 180)
			(size 5 2.5)
			(drill oval 3.5 1)
			(layers "*.Cu" "*.Mask")
			(remove_unused_layers no)
			(net "NetD1_2")
		)
		(pad "2" thru_hole oval
			(at 6 0 180)
			(size 4.5 2.25)
			(drill oval 3 1)
			(layers "*.Cu" "*.Mask")
			(remove_unused_layers no)
			(net "GND")
		)
		(pad "3" thru_hole oval
			(at 3 -4.7 270)
			(size 4.5 2.25)
			(drill oval 3 1)
			(layers "*.Cu" "*.Mask")
			(remove_unused_layers no)
			(net "GND")
		)
	)
	(footprint "Vault:CAPC1608X87X45ML20T05"
		(layer "F.Cu")
		(at 154.288595 81.5786 90)
		(property "Reference" "C66"
			(at -4.3 0.393345 90)
			(unlocked yes)
			(layer "F.SilkS")
			(effects
				(font
					(size 0.762 0.762)
					(thickness 0.2286)
				)
				(justify left bottom)
			)
		)
		(property "Value" "0.1uF"
			(at -3.47599 -0.2921 0)
			(unlocked yes)
			(layer "F.SilkS")
			(hide yes)
			(effects
				(font
					(size 1.524 1.524)
					(thickness 0.254)
				)
				(justify left bottom)
			)
		)
		(sheetname "MAC")
		(sheetfile "MAC.kicad_sch")
		(duplicate_pad_numbers_are_jumpers no)
		(pad "1" smd rect
			(at -0.7 0 180)
			(size 1.1 1.05)
			(layers "F.Cu" "F.Mask" "F.Paste")
			(net "GND")
		)
		(pad "2" smd rect
			(at 0.7 0 180)
			(size 1.1 1.05)
			(layers "F.Cu" "F.Mask" "F.Paste")
			(net "+3.3V_CLEAN")
		)
	)
	(footprint "Vault:TECO-1909763-1_V"
		(layer "F.Cu")
		(at 75.088595 97.5786 90)
		(property "Reference" "J6"
			(at -2.726931 2.028605 0)
			(unlocked yes)
			(layer "F.SilkS")
			(effects
				(font
					(size 0.762 0.762)
					(thickness 0.2286)
				)
			)
		)
		(property "Value" "1909763-1"
			(at 4.608085 3.749802 90)
			(unlocked yes)
			(layer "F.SilkS")
			(hide yes)
			(effects
				(font
					(size 1.524 1.524)
					(thickness 0.254)
				)
			)
		)
		(sheetname "USER_IO")
		(sheetfile "USER_IO.kicad_sch")
		(duplicate_pad_numbers_are_jumpers no)
		(fp_line
			(start -0.55 -1.3)
			(end 0.55 -1.3)
			(stroke
				(width 0.2)
				(type solid)
			)
			(layer "F.SilkS")
		)
		(fp_circle
			(center -1.778 1.65)
			(end -1.653 1.65)
			(stroke
				(width 0.25)
				(type solid)
			)
			(fill no)
			(layer "F.SilkS")
		)
		(pad "1" smd rect
			(at -1.475 0 90)
			(size 1.05 2.2)
			(layers "F.Cu" "F.Mask" "F.Paste")
			(net "GND")
		)
		(pad "2" smd rect
			(at 0 1.525 90)
			(size 1 1.05)
			(layers "F.Cu" "F.Mask" "F.Paste")
			(net "ANT1")
		)
		(pad "3" smd rect
			(at 1.475 0 90)
			(size 1.05 2.2)
			(layers "F.Cu" "F.Mask" "F.Paste")
			(net "GND")
		)
	)
	(footprint "Vault:CAPC1608X87X45ML20T05"
		(layer "F.Cu")
		(at 137.888595 90.4786 90)
		(property "Reference" "C24"
			(at -2.9714 -0.073069 90)
			(unlocked yes)
			(layer "F.SilkS")
			(effects
				(font
					(size 0.762 0.762)
					(thickness 0.2286)
				)
			)
		)
		(property "Value" "0.1uF"
			(at 2.09443 2.657602 90)
			(unlocked yes)
			(layer "F.SilkS")
			(hide yes)
			(effects
				(font
					(size 1.524 1.524)
					(thickness 0.254)
				)
			)
		)
		(sheetname "GPS_IMU_SENSORS")
		(sheetfile "GPS_IMU_SENSORS.kicad_sch")
		(duplicate_pad_numbers_are_jumpers no)
		(pad "1" smd rect
			(at -0.7 0 180)
			(size 1.1 1.05)
			(layers "F.Cu" "F.Mask" "F.Paste")
			(net "GND")
		)
		(pad "2" smd rect
			(at 0.7 0 180)
			(size 1.1 1.05)
			(layers "F.Cu" "F.Mask" "F.Paste")
			(net "+3.3V_CLEAN")
		)
	)
	(footprint "Capacitors:CAPC1608X10N"
		(layer "F.Cu")
		(at 226.251595 76.8586 -90)
		(property "Reference" "C86"
			(at -1.98 -0.430345 90)
			(unlocked yes)
			(layer "F.SilkS")
			(effects
				(font
					(size 0.762 0.762)
					(thickness 0.2286)
				)
				(justify left bottom)
			)
		)
		(property "Value" "CAP_0603_22PF_50V"
			(at 7.89559 -10.3759 0)
			(unlocked yes)
			(layer "F.SilkS")
			(hide yes)
			(effects
				(font
					(size 1.524 1.524)
					(thickness 0.254)
				)
				(justify left bottom)
			)
		)
		(sheetname "GPS_IMU_SENSORS")
		(sheetfile "GPS_IMU_SENSORS.kicad_sch")
		(duplicate_pad_numbers_are_jumpers no)
		(fp_line
			(start 0.635 0.7112)
			(end -0.635 0.7112)
			(stroke
				(width 0.1524)
				(type solid)
			)
			(layer "F.SilkS")
		)
		(fp_line
			(start 0.635 -0.7112)
			(end -0.635 -0.7112)
			(stroke
				(width 0.1524)
				(type solid)
			)
			(layer "F.SilkS")
		)
		(pad "1" smd rect
			(at -0.8 0)
			(size 0.95 1)
			(layers "F.Cu" "F.Mask" "F.Paste")
			(net "GND")
		)
		(pad "2" smd rect
			(at 0.8 0)
			(size 0.95 1)
			(layers "F.Cu" "F.Mask" "F.Paste")
			(net "NetC86_2")
		)
	)
	(footprint "Vault:CAPC1608X87X45ML20T05"
		(layer "F.Cu")
		(at 227.648595 115.4666)
		(property "Reference" "C18"
			(at 1.74 0.905345 0)
			(unlocked yes)
			(layer "F.SilkS")
			(effects
				(font
					(size 0.762 0.762)
					(thickness 0.2286)
				)
				(justify left bottom)
			)
		)
		(property "Value" "0.1uF"
			(at 3.0099 9.82599 0)
			(unlocked yes)
			(layer "F.SilkS")
			(hide yes)
			(effects
				(font
					(size 1.524 1.524)
					(thickness 0.254)
				)
				(justify left bottom)
			)
		)
		(sheetname "POWER")
		(sheetfile "POWER.kicad_sch")
		(duplicate_pad_numbers_are_jumpers no)
		(pad "1" smd rect
			(at -0.7 0 90)
			(size 1.1 1.05)
			(layers "F.Cu" "F.Mask" "F.Paste")
			(net "GND")
		)
		(pad "2" smd rect
			(at 0.7 0 90)
			(size 1.1 1.05)
			(layers "F.Cu" "F.Mask" "F.Paste")
			(net "+5.0V")
		)
	)
	(footprint "Passives:DIOM1608X06N"
		(layer "F.Cu")
		(at 90.234595 53.2366 90)
		(property "Reference" "D14"
			(at -1.47909 -1.367335 90)
			(unlocked yes)
			(layer "F.SilkS")
			(effects
				(font
					(size 0.762 0.762)
					(thickness 0.2286)
				)
				(justify left bottom)
			)
		)
		(property "Value" "RED"
			(at -4.13639 -0.5715 0)
			(unlocked yes)
			(layer "F.SilkS")
			(hide yes)
			(effects
				(font
					(size 1.524 1.524)
					(thickness 0.254)
				)
				(justify left bottom)
			)
		)
		(sheetname "USER_IO")
		(sheetfile "USER_IO.kicad_sch")
		(duplicate_pad_numbers_are_jumpers no)
		(fp_circle
			(center -1.275 -0.725)
			(end -1.225 -0.725)
			(stroke
				(width 0.1)
				(type solid)
			)
			(fill no)
			(layer "F.SilkS")
		)
		(pad "1" smd rect
			(at -0.725 0 180)
			(size 0.85 1)
			(layers "F.Cu" "F.Mask" "F.Paste")
			(net "NetD14_1")
		)
		(pad "2" smd rect
			(at 0.725 0 180)
			(size 0.85 1)
			(layers "F.Cu" "F.Mask" "F.Paste")
			(net "+3.3V")
		)
	)
	(footprint "Capacitors:CAPC2012X14N"
		(layer "F.Cu")
		(at 220.088595 87.9786 90)
		(property "Reference" "C8"
			(at 3 0.393345 90)
			(unlocked yes)
			(layer "F.SilkS")
			(effects
				(font
					(size 0.762 0.762)
					(thickness 0.2286)
				)
				(justify left bottom)
			)
		)
		(property "Value" "CAP_0805_10UF_25V"
			(at -10.63879 10.0965 0)
			(unlocked yes)
			(layer "F.SilkS")
			(hide yes)
			(effects
				(font
					(size 1.524 1.524)
					(thickness 0.254)
				)
				(justify left bottom)
			)
		)
		(sheetname "POWER")
		(sheetfile "POWER.kicad_sch")
		(duplicate_pad_numbers_are_jumpers no)
		(fp_line
			(start -0.762 -0.9652)
			(end 0.762 -0.9652)
			(stroke
				(width 0.1524)
				(type solid)
			)
			(layer "F.SilkS")
		)
		(fp_line
			(start -0.762 0.9652)
			(end 0.762 0.9652)
			(stroke
				(width 0.1524)
				(type solid)
			)
			(layer "F.SilkS")
		)
		(pad "1" smd rect
			(at -0.9 0 180)
			(size 1.45 1.15)
			(layers "F.Cu" "F.Mask" "F.Paste")
			(net "+3.3V")
		)
		(pad "2" smd rect
			(at 0.9 0 180)
			(size 1.45 1.15)
			(layers "F.Cu" "F.Mask" "F.Paste")
			(net "GND")
		)
	)
)
